#ISCELL
  pure_quanta quanta_title_block_c *
  *
#CELL
  pure_quanta genoa_sp5 *
  page49_i213
#CELL
  pure_quanta genoa_sp5 *
  page49_i214
#ISCELL
  standard offpage *
  page49_i232
#ISCELL
  mstr_standard tap *
  page49_i235
#ISCELL
  mstr_standard tap *
  page49_i236
#ISCELL
  standard tap *
  page49_i240
#ISCELL
  standard tap *
  page49_i241
#ISCELL
  standard tap *
  page49_i244
#ISCELL
  standard tap *
  page49_i245
#ISCELL
  standard tap *
  page49_i246
#ISCELL
  standard tap *
  page49_i250
#ISCELL
  standard tap *
  page49_i251
#ISCELL
  standard tap *
  page49_i254
#ISCELL
  standard tap *
  page49_i255
#ISCELL
  standard tap *
  page49_i256
#ISCELL
  standard tap *
  page49_i260
#ISCELL
  standard tap *
  page49_i261
#ISCELL
  standard tap *
  page49_i264
#ISCELL
  standard tap *
  page49_i265
#ISCELL
  standard offpage *
  page49_i267
#ISCELL
  mstr_standard tap *
  page49_i270
#ISCELL
  standard tap *
  page49_i271
#ISCELL
  mstr_standard tap *
  page49_i272
#ISCELL
  standard tap *
  page49_i276
#ISCELL
  standard tap *
  page49_i277
#ISCELL
  standard tap *
  page49_i280
#ISCELL
  standard tap *
  page49_i281
#ISCELL
  standard tap *
  page49_i282
#ISCELL
  standard tap *
  page49_i286
#ISCELL
  standard tap *
  page49_i287
#ISCELL
  standard tap *
  page49_i290
#ISCELL
  standard tap *
  page49_i291
#ISCELL
  standard tap *
  page49_i292
#ISCELL
  standard tap *
  page49_i296
#ISCELL
  standard tap *
  page49_i297
#ISCELL
  standard tap *
  page49_i298
#ISCELL
  mstr_standard tap *
  page49_i300
#ISCELL
  mstr_standard tap *
  page49_i301
#ISCELL
  mstr_standard tap *
  page49_i303
#ISCELL
  standard tap *
  page49_i304
#ISCELL
  standard tap *
  page49_i308
#ISCELL
  standard tap *
  page49_i309
#ISCELL
  standard tap *
  page49_i310
#ISCELL
  standard tap *
  page49_i313
#ISCELL
  standard tap *
  page49_i314
#ISCELL
  standard tap *
  page49_i318
#ISCELL
  standard tap *
  page49_i319
#ISCELL
  standard tap *
  page49_i320
#ISCELL
  standard tap *
  page49_i323
#ISCELL
  standard tap *
  page49_i324
#ISCELL
  standard tap *
  page49_i328
#ISCELL
  standard tap *
  page49_i329
#ISCELL
  standard offpage *
  page49_i333
#ISCELL
  mstr_standard tap *
  page49_i334
#ISCELL
  mstr_standard tap *
  page49_i335
#ISCELL
  mstr_standard tap *
  page49_i336
#ISCELL
  standard tap *
  page49_i339
#ISCELL
  standard tap *
  page49_i340
#ISCELL
  standard tap *
  page49_i344
#ISCELL
  standard tap *
  page49_i345
#ISCELL
  standard tap *
  page49_i346
#ISCELL
  standard tap *
  page49_i349
#ISCELL
  standard tap *
  page49_i350
#ISCELL
  standard offpage *
  page49_i355
#ISCELL
  standard tap *
  page49_i356
#ISCELL
  standard tap *
  page49_i357
#ISCELL
  standard tap *
  page49_i358
#ISCELL
  standard tap *
  page49_i361
#ISCELL
  standard tap *
  page49_i362
#ISCELL
  standard tap *
  page49_i366
#ISCELL
  standard offpage *
  page49_i436
#ISCELL
  mstr_standard tap *
  page49_i437
#ISCELL
  mstr_standard tap *
  page49_i438
#ISCELL
  standard tap *
  page49_i439
#ISCELL
  standard tap *
  page49_i440
#ISCELL
  standard tap *
  page49_i441
#ISCELL
  standard tap *
  page49_i442
#ISCELL
  standard tap *
  page49_i443
#ISCELL
  standard tap *
  page49_i444
#ISCELL
  standard tap *
  page49_i445
#ISCELL
  standard tap *
  page49_i446
#ISCELL
  standard tap *
  page49_i447
#ISCELL
  standard tap *
  page49_i448
#ISCELL
  standard tap *
  page49_i449
#ISCELL
  standard tap *
  page49_i450
#ISCELL
  standard tap *
  page49_i451
#ISCELL
  standard tap *
  page49_i452
#ISCELL
  mstr_standard tap *
  page49_i453
#ISCELL
  mstr_standard tap *
  page49_i454
#ISCELL
  standard tap *
  page49_i455
#ISCELL
  standard tap *
  page49_i456
#ISCELL
  standard tap *
  page49_i457
#ISCELL
  standard tap *
  page49_i458
#ISCELL
  standard tap *
  page49_i459
#ISCELL
  standard tap *
  page49_i460
#ISCELL
  standard tap *
  page49_i461
#ISCELL
  standard tap *
  page49_i462
#ISCELL
  standard tap *
  page49_i463
#ISCELL
  standard tap *
  page49_i464
#ISCELL
  standard tap *
  page49_i465
#ISCELL
  standard tap *
  page49_i466
#ISCELL
  standard tap *
  page49_i467
#ISCELL
  standard tap *
  page49_i468
#ISCELL
  standard offpage *
  page49_i469
#ISCELL
  mstr_standard tap *
  page49_i470
#ISCELL
  mstr_standard tap *
  page49_i471
#ISCELL
  standard tap *
  page49_i472
#ISCELL
  standard tap *
  page49_i473
#ISCELL
  standard tap *
  page49_i474
#ISCELL
  standard tap *
  page49_i475
#ISCELL
  standard tap *
  page49_i476
#ISCELL
  standard tap *
  page49_i477
#ISCELL
  standard tap *
  page49_i478
#ISCELL
  standard tap *
  page49_i479
#ISCELL
  standard tap *
  page49_i480
#ISCELL
  standard tap *
  page49_i481
#ISCELL
  standard tap *
  page49_i482
#ISCELL
  standard tap *
  page49_i483
#ISCELL
  standard tap *
  page49_i484
#ISCELL
  standard tap *
  page49_i485
#ISCELL
  standard offpage *
  page49_i486
#ISCELL
  standard offpage *
  page49_i487
#ISCELL
  mstr_standard tap *
  page49_i488
#ISCELL
  mstr_standard tap *
  page49_i489
#ISCELL
  standard tap *
  page49_i490
#ISCELL
  standard tap *
  page49_i491
#ISCELL
  standard tap *
  page49_i492
#ISCELL
  standard tap *
  page49_i493
#ISCELL
  standard tap *
  page49_i494
#ISCELL
  standard tap *
  page49_i495
#ISCELL
  standard tap *
  page49_i496
#ISCELL
  standard tap *
  page49_i497
#ISCELL
  standard tap *
  page49_i498
#ISCELL
  standard tap *
  page49_i499
#ISCELL
  standard tap *
  page49_i500
#ISCELL
  standard tap *
  page49_i501
#ISCELL
  standard tap *
  page49_i502
#ISCELL
  standard tap *
  page49_i503
